(kicad_pcb
	(version 20260206)
	(generator "pcbnew")
	(generator_version "10.0")
	(general
		(thickness 1.6)
		(legacy_teardrops no)
	)
	(paper "A4")
	(title_block
		(title "01162023_DA0F0TEBIF0_F0T_Expander_BD_F_brd_V02_OCP.brd")
		(comment 1 "Grand Teton / footprints 5141-5148 of 9728")
	)
	(layers
		(0 "F.Cu" signal "TOP")
		(4 "In1.Cu" signal "GND")
		(6 "In2.Cu" signal "VCC")
		(8 "In3.Cu" signal "VCC1")
		(10 "In4.Cu" signal "GND1")
		(12 "In5.Cu" signal "IN1")
		(14 "In6.Cu" signal "GND2")
		(16 "In7.Cu" signal "IN2")
		(18 "In8.Cu" signal "GND3")
		(20 "In9.Cu" signal "IN3")
		(22 "In10.Cu" signal "GND4")
		(24 "In11.Cu" signal "IN4")
		(26 "In12.Cu" signal "GND5")
		(28 "In13.Cu" signal "IN5")
		(30 "In14.Cu" signal "GND6")
		(32 "In15.Cu" signal "IN6")
		(34 "In16.Cu" signal "GND7")
		(2 "B.Cu" signal "BOTTOM")
		(9 "F.Adhes" user "F.Adhesive")
		(11 "B.Adhes" user "B.Adhesive")
		(13 "F.Paste" user "Package Geometry/Pastemask Top")
		(15 "B.Paste" user "Package Geometry/Pastemask Bottom")
		(5 "F.SilkS" user "Ref Des/Silkscreen Top")
		(7 "B.SilkS" user "Ref Des/Silkscreen Bottom")
		(1 "F.Mask" user "Board Geometry/Soldermask Top")
		(3 "B.Mask" user "Board Geometry/Soldermask Bottom")
		(17 "Dwgs.User" user "User.Drawings")
		(19 "Cmts.User" user "User.Comments")
		(21 "Eco1.User" user "User.Eco1")
		(23 "Eco2.User" user "User.Eco2")
		(25 "Edge.Cuts" user "Board Geometry/Outline")
		(27 "Margin" user)
		(31 "F.CrtYd" user "Package Geometry/Place Bound Top")
		(29 "B.CrtYd" user "Package Geometry/Place Bound Bottom")
		(35 "F.Fab" user "Ref Des/Assembly Top")
		(33 "B.Fab" user "Ref Des/Assembly Bottom")
	)
	(footprint ""
		(layer "F.Cu")
		(at 2.87528 -68.166234 180)
		(property "Reference" "R5876"
			(at 0 0 180)
			(layer "F.SilkS")
			(hide yes)
			(effects
				(font
					(size 1.27 1.27)
				)
			)
		)
		(property "Value" ""
			(at 0 0 180)
			(layer "F.Fab")
			(effects
				(font
					(size 1.27 1.27)
				)
			)
		)
		(duplicate_pad_numbers_are_jumpers no)
		(fp_line
			(start 0.7874 0.4064)
			(end -0.7874 0.4064)
			(stroke
				(width 0.1524)
				(type default)
			)
			(layer "F.SilkS")
		)
		(fp_line
			(start 0.7874 -0.4064)
			(end 0.7874 0.4064)
			(stroke
				(width 0.1524)
				(type default)
			)
			(layer "F.SilkS")
		)
		(fp_line
			(start -0.7874 0.4064)
			(end -0.7874 -0.4064)
			(stroke
				(width 0.1524)
				(type default)
			)
			(layer "F.SilkS")
		)
		(fp_line
			(start -0.7874 -0.4064)
			(end 0.7874 -0.4064)
			(stroke
				(width 0.1524)
				(type default)
			)
			(layer "F.SilkS")
		)
		(fp_line
			(start 0.67945 0.3048)
			(end 0.120396 0.3048)
			(stroke
				(width 0.1)
				(type default)
			)
			(layer "F.Fab")
		)
		(fp_line
			(start 0.67945 -0.3048)
			(end 0.67945 0.3048)
			(stroke
				(width 0.1)
				(type default)
			)
			(layer "F.Fab")
		)
		(fp_line
			(start 0.12065 -0.2794)
			(end 0.12065 -0.3048)
			(stroke
				(width 0.1)
				(type default)
			)
			(layer "F.Fab")
		)
		(fp_line
			(start 0.12065 -0.3048)
			(end 0.67945 -0.3048)
			(stroke
				(width 0.1)
				(type default)
			)
			(layer "F.Fab")
		)
		(fp_line
			(start 0.120396 0.3048)
			(end 0.120396 0.2794)
			(stroke
				(width 0.1)
				(type default)
			)
			(layer "F.Fab")
		)
		(fp_line
			(start 0.120396 0.2794)
			(end -0.12065 0.2794)
			(stroke
				(width 0.1)
				(type default)
			)
			(layer "F.Fab")
		)
		(fp_line
			(start -0.12065 0.3048)
			(end -0.67945 0.3048)
			(stroke
				(width 0.1)
				(type default)
			)
			(layer "F.Fab")
		)
		(fp_line
			(start -0.12065 0.2794)
			(end -0.12065 0.3048)
			(stroke
				(width 0.1)
				(type default)
			)
			(layer "F.Fab")
		)
		(fp_line
			(start -0.12065 -0.2794)
			(end 0.12065 -0.2794)
			(stroke
				(width 0.1)
				(type default)
			)
			(layer "F.Fab")
		)
		(fp_line
			(start -0.12065 -0.305054)
			(end -0.12065 -0.2794)
			(stroke
				(width 0.1)
				(type default)
			)
			(layer "F.Fab")
		)
		(fp_line
			(start -0.67945 0.3048)
			(end -0.67945 -0.305054)
			(stroke
				(width 0.1)
				(type default)
			)
			(layer "F.Fab")
		)
		(fp_line
			(start -0.67945 -0.305054)
			(end -0.12065 -0.305054)
			(stroke
				(width 0.1)
				(type default)
			)
			(layer "F.Fab")
		)
		(pad "1" smd circle
			(at -0.40005 0 180)
			(size 0 0)
			(layers "F.Cu" "F.Mask" "F.Paste")
			(net "P3V3_SSD0_PG_G1")
		)
		(pad "2" smd circle
			(at 0.40005 0 180)
			(size 0 0)
			(layers "F.Cu" "F.Mask" "F.Paste")
			(net "GND")
		)
	)
	(footprint ""
		(layer "F.Cu")
		(at 372.07698 -350.098614 90)
		(property "Reference" "C779"
			(at 0 0 90)
			(layer "F.SilkS")
			(hide yes)
			(effects
				(font
					(size 1.27 1.27)
				)
			)
		)
		(property "Value" ""
			(at 0 0 90)
			(layer "F.Fab")
			(effects
				(font
					(size 1.27 1.27)
				)
			)
		)
		(duplicate_pad_numbers_are_jumpers no)
		(fp_line
			(start 0.299974 -0.150114)
			(end 0.299974 0.150114)
			(stroke
				(width 0.1)
				(type default)
			)
			(layer "F.Fab")
		)
		(fp_line
			(start -0.299974 -0.150114)
			(end 0.299974 -0.150114)
			(stroke
				(width 0.1)
				(type default)
			)
			(layer "F.Fab")
		)
		(fp_line
			(start 0.299974 0.150114)
			(end -0.299974 0.150114)
			(stroke
				(width 0.1)
				(type default)
			)
			(layer "F.Fab")
		)
		(fp_line
			(start -0.299974 0.150114)
			(end -0.299974 -0.150114)
			(stroke
				(width 0.1)
				(type default)
			)
			(layer "F.Fab")
		)
		(pad "1" smd rect
			(at -0.2667 0 90)
			(size 0.3048 0.381)
			(layers "F.Cu" "F.Mask" "F.Paste")
			(net "P5E_PEX3_STN6_TX_DN<103>")
		)
		(pad "2" smd rect
			(at 0.2667 0 90)
			(size 0.3048 0.381)
			(layers "F.Cu" "F.Mask" "F.Paste")
			(net "P5E_PEX3_STN6_TX_C_DN<103>")
		)
	)
	(footprint ""
		(layer "F.Cu")
		(at 380.48946 -350.098614 90)
		(property "Reference" "C770"
			(at 0 0 90)
			(layer "F.SilkS")
			(hide yes)
			(effects
				(font
					(size 1.27 1.27)
				)
			)
		)
		(property "Value" ""
			(at 0 0 90)
			(layer "F.Fab")
			(effects
				(font
					(size 1.27 1.27)
				)
			)
		)
		(duplicate_pad_numbers_are_jumpers no)
		(fp_line
			(start 0.299974 -0.150114)
			(end 0.299974 0.150114)
			(stroke
				(width 0.1)
				(type default)
			)
			(layer "F.Fab")
		)
		(fp_line
			(start -0.299974 -0.150114)
			(end 0.299974 -0.150114)
			(stroke
				(width 0.1)
				(type default)
			)
			(layer "F.Fab")
		)
		(fp_line
			(start 0.299974 0.150114)
			(end -0.299974 0.150114)
			(stroke
				(width 0.1)
				(type default)
			)
			(layer "F.Fab")
		)
		(fp_line
			(start -0.299974 0.150114)
			(end -0.299974 -0.150114)
			(stroke
				(width 0.1)
				(type default)
			)
			(layer "F.Fab")
		)
		(pad "1" smd rect
			(at -0.2667 0 90)
			(size 0.3048 0.381)
			(layers "F.Cu" "F.Mask" "F.Paste")
			(net "P5E_PEX3_STN6_TX_DP<107>")
		)
		(pad "2" smd rect
			(at 0.2667 0 90)
			(size 0.3048 0.381)
			(layers "F.Cu" "F.Mask" "F.Paste")
			(net "P5E_PEX3_STN6_TX_C_DP<107>")
		)
	)
	(footprint ""
		(layer "F.Cu")
		(at 462.465674 -277.65883)
		(property "Reference" "R805"
			(at 0 0 0)
			(layer "F.SilkS")
			(hide yes)
			(effects
				(font
					(size 1.27 1.27)
				)
			)
		)
		(property "Value" ""
			(at 0 0 0)
			(layer "F.Fab")
			(effects
				(font
					(size 1.27 1.27)
				)
			)
		)
		(duplicate_pad_numbers_are_jumpers no)
		(fp_line
			(start -0.7874 -0.4064)
			(end 0.7874 -0.4064)
			(stroke
				(width 0.1524)
				(type default)
			)
			(layer "F.SilkS")
		)
		(fp_line
			(start -0.7874 0.4064)
			(end -0.7874 -0.4064)
			(stroke
				(width 0.1524)
				(type default)
			)
			(layer "F.SilkS")
		)
		(fp_line
			(start 0.7874 -0.4064)
			(end 0.7874 0.4064)
			(stroke
				(width 0.1524)
				(type default)
			)
			(layer "F.SilkS")
		)
		(fp_line
			(start 0.7874 0.4064)
			(end -0.7874 0.4064)
			(stroke
				(width 0.1524)
				(type default)
			)
			(layer "F.SilkS")
		)
		(fp_line
			(start -0.67945 -0.305054)
			(end -0.12065 -0.305054)
			(stroke
				(width 0.1)
				(type default)
			)
			(layer "F.Fab")
		)
		(fp_line
			(start -0.67945 0.3048)
			(end -0.67945 -0.305054)
			(stroke
				(width 0.1)
				(type default)
			)
			(layer "F.Fab")
		)
		(fp_line
			(start -0.12065 -0.305054)
			(end -0.12065 -0.2794)
			(stroke
				(width 0.1)
				(type default)
			)
			(layer "F.Fab")
		)
		(fp_line
			(start -0.12065 -0.2794)
			(end 0.12065 -0.2794)
			(stroke
				(width 0.1)
				(type default)
			)
			(layer "F.Fab")
		)
		(fp_line
			(start -0.12065 0.2794)
			(end -0.12065 0.3048)
			(stroke
				(width 0.1)
				(type default)
			)
			(layer "F.Fab")
		)
		(fp_line
			(start -0.12065 0.3048)
			(end -0.67945 0.3048)
			(stroke
				(width 0.1)
				(type default)
			)
			(layer "F.Fab")
		)
		(fp_line
			(start 0.120396 0.2794)
			(end -0.12065 0.2794)
			(stroke
				(width 0.1)
				(type default)
			)
			(layer "F.Fab")
		)
		(fp_line
			(start 0.120396 0.3048)
			(end 0.120396 0.2794)
			(stroke
				(width 0.1)
				(type default)
			)
			(layer "F.Fab")
		)
		(fp_line
			(start 0.12065 -0.3048)
			(end 0.67945 -0.3048)
			(stroke
				(width 0.1)
				(type default)
			)
			(layer "F.Fab")
		)
		(fp_line
			(start 0.12065 -0.2794)
			(end 0.12065 -0.3048)
			(stroke
				(width 0.1)
				(type default)
			)
			(layer "F.Fab")
		)
		(fp_line
			(start 0.67945 -0.3048)
			(end 0.67945 0.3048)
			(stroke
				(width 0.1)
				(type default)
			)
			(layer "F.Fab")
		)
		(fp_line
			(start 0.67945 0.3048)
			(end 0.120396 0.3048)
			(stroke
				(width 0.1)
				(type default)
			)
			(layer "F.Fab")
		)
		(pad "1" smd circle
			(at -0.40005 0)
			(size 0 0)
			(layers "F.Cu" "F.Mask" "F.Paste")
			(net "PEX3_P1V25_ADC_ALERT_N")
		)
		(pad "2" smd circle
			(at 0.40005 0)
			(size 0 0)
			(layers "F.Cu" "F.Mask" "F.Paste")
			(net "PEX_ADC_ALERT_N")
		)
	)
	(footprint ""
		(layer "F.Cu")
		(at 312.21934 -147.104608 180)
		(property "Reference" "C433"
			(at 0 0 180)
			(layer "F.SilkS")
			(hide yes)
			(effects
				(font
					(size 1.27 1.27)
				)
			)
		)
		(property "Value" ""
			(at 0 0 180)
			(layer "F.Fab")
			(effects
				(font
					(size 1.27 1.27)
				)
			)
		)
		(duplicate_pad_numbers_are_jumpers no)
		(fp_line
			(start 0.299974 0.150114)
			(end -0.299974 0.150114)
			(stroke
				(width 0.1)
				(type default)
			)
			(layer "F.Fab")
		)
		(fp_line
			(start 0.299974 -0.150114)
			(end 0.299974 0.150114)
			(stroke
				(width 0.1)
				(type default)
			)
			(layer "F.Fab")
		)
		(fp_line
			(start -0.299974 0.150114)
			(end -0.299974 -0.150114)
			(stroke
				(width 0.1)
				(type default)
			)
			(layer "F.Fab")
		)
		(fp_line
			(start -0.299974 -0.150114)
			(end 0.299974 -0.150114)
			(stroke
				(width 0.1)
				(type default)
			)
			(layer "F.Fab")
		)
		(pad "1" smd rect
			(at -0.2667 0 180)
			(size 0.3048 0.381)
			(layers "F.Cu" "F.Mask" "F.Paste")
			(net "P5E_PEX2_STN0_TX_DP<10>")
		)
		(pad "2" smd rect
			(at 0.2667 0 180)
			(size 0.3048 0.381)
			(layers "F.Cu" "F.Mask" "F.Paste")
			(net "P5E_PEX2_STN0_TX_C_DP<10>")
		)
	)
	(footprint ""
		(layer "F.Cu")
		(at 159.966152 -356.244906 90)
		(property "Reference" "C403"
			(at 0 0 90)
			(layer "F.SilkS")
			(hide yes)
			(effects
				(font
					(size 1.27 1.27)
				)
			)
		)
		(property "Value" ""
			(at 0 0 90)
			(layer "F.Fab")
			(effects
				(font
					(size 1.27 1.27)
				)
			)
		)
		(duplicate_pad_numbers_are_jumpers no)
		(fp_line
			(start 0.299974 -0.150114)
			(end 0.299974 0.150114)
			(stroke
				(width 0.1)
				(type default)
			)
			(layer "F.Fab")
		)
		(fp_line
			(start -0.299974 -0.150114)
			(end 0.299974 -0.150114)
			(stroke
				(width 0.1)
				(type default)
			)
			(layer "F.Fab")
		)
		(fp_line
			(start 0.299974 0.150114)
			(end -0.299974 0.150114)
			(stroke
				(width 0.1)
				(type default)
			)
			(layer "F.Fab")
		)
		(fp_line
			(start -0.299974 0.150114)
			(end -0.299974 -0.150114)
			(stroke
				(width 0.1)
				(type default)
			)
			(layer "F.Fab")
		)
		(pad "1" smd rect
			(at -0.2667 0 90)
			(size 0.3048 0.381)
			(layers "F.Cu" "F.Mask" "F.Paste")
			(net "P5E_PEX1_STN7_TX_DN<112>")
		)
		(pad "2" smd rect
			(at 0.2667 0 90)
			(size 0.3048 0.381)
			(layers "F.Cu" "F.Mask" "F.Paste")
			(net "P5E_PEX1_STN7_TX_C_DN<112>")
		)
	)
	(footprint ""
		(layer "F.Cu")
		(at 377.175268 -64.102234 180)
		(property "Reference" "PR7092"
			(at 0 0 180)
			(layer "F.SilkS")
			(hide yes)
			(effects
				(font
					(size 1.27 1.27)
				)
			)
		)
		(property "Value" ""
			(at 0 0 180)
			(layer "F.Fab")
			(effects
				(font
					(size 1.27 1.27)
				)
			)
		)
		(duplicate_pad_numbers_are_jumpers no)
		(fp_line
			(start 0.7874 0.4064)
			(end -0.7874 0.4064)
			(stroke
				(width 0.1524)
				(type default)
			)
			(layer "F.SilkS")
		)
		(fp_line
			(start 0.7874 -0.4064)
			(end 0.7874 0.4064)
			(stroke
				(width 0.1524)
				(type default)
			)
			(layer "F.SilkS")
		)
		(fp_line
			(start -0.7874 0.4064)
			(end -0.7874 -0.4064)
			(stroke
				(width 0.1524)
				(type default)
			)
			(layer "F.SilkS")
		)
		(fp_line
			(start -0.7874 -0.4064)
			(end 0.7874 -0.4064)
			(stroke
				(width 0.1524)
				(type default)
			)
			(layer "F.SilkS")
		)
		(fp_line
			(start 0.67945 0.3048)
			(end 0.120396 0.3048)
			(stroke
				(width 0.1)
				(type default)
			)
			(layer "F.Fab")
		)
		(fp_line
			(start 0.67945 -0.3048)
			(end 0.67945 0.3048)
			(stroke
				(width 0.1)
				(type default)
			)
			(layer "F.Fab")
		)
		(fp_line
			(start 0.12065 -0.2794)
			(end 0.12065 -0.3048)
			(stroke
				(width 0.1)
				(type default)
			)
			(layer "F.Fab")
		)
		(fp_line
			(start 0.12065 -0.3048)
			(end 0.67945 -0.3048)
			(stroke
				(width 0.1)
				(type default)
			)
			(layer "F.Fab")
		)
		(fp_line
			(start 0.120396 0.3048)
			(end 0.120396 0.2794)
			(stroke
				(width 0.1)
				(type default)
			)
			(layer "F.Fab")
		)
		(fp_line
			(start 0.120396 0.2794)
			(end -0.12065 0.2794)
			(stroke
				(width 0.1)
				(type default)
			)
			(layer "F.Fab")
		)
		(fp_line
			(start -0.12065 0.3048)
			(end -0.67945 0.3048)
			(stroke
				(width 0.1)
				(type default)
			)
			(layer "F.Fab")
		)
		(fp_line
			(start -0.12065 0.2794)
			(end -0.12065 0.3048)
			(stroke
				(width 0.1)
				(type default)
			)
			(layer "F.Fab")
		)
		(fp_line
			(start -0.12065 -0.2794)
			(end 0.12065 -0.2794)
			(stroke
				(width 0.1)
				(type default)
			)
			(layer "F.Fab")
		)
		(fp_line
			(start -0.12065 -0.305054)
			(end -0.12065 -0.2794)
			(stroke
				(width 0.1)
				(type default)
			)
			(layer "F.Fab")
		)
		(fp_line
			(start -0.67945 0.3048)
			(end -0.67945 -0.305054)
			(stroke
				(width 0.1)
				(type default)
			)
			(layer "F.Fab")
		)
		(fp_line
			(start -0.67945 -0.305054)
			(end -0.12065 -0.305054)
			(stroke
				(width 0.1)
				(type default)
			)
			(layer "F.Fab")
		)
		(pad "1" smd circle
			(at -0.40005 0 180)
			(size 0 0)
			(layers "F.Cu" "F.Mask" "F.Paste")
			(net "P12V_SSD13_PG_G1")
		)
		(pad "2" smd circle
			(at 0.40005 0 180)
			(size 0 0)
			(layers "F.Cu" "F.Mask" "F.Paste")
			(net "GND")
		)
	)
	(footprint ""
		(layer "F.Cu")
		(at 202.311 -61.386974)
		(property "Reference" "R4494"
			(at 0 0 0)
			(layer "F.SilkS")
			(hide yes)
			(effects
				(font
					(size 1.27 1.27)
				)
			)
		)
		(property "Value" ""
			(at 0 0 0)
			(layer "F.Fab")
			(effects
				(font
					(size 1.27 1.27)
				)
			)
		)
		(duplicate_pad_numbers_are_jumpers no)
		(fp_line
			(start -0.7874 -0.4064)
			(end 0.7874 -0.4064)
			(stroke
				(width 0.1524)
				(type default)
			)
			(layer "F.SilkS")
		)
		(fp_line
			(start -0.7874 0.4064)
			(end -0.7874 -0.4064)
			(stroke
				(width 0.1524)
				(type default)
			)
			(layer "F.SilkS")
		)
		(fp_line
			(start 0.7874 -0.4064)
			(end 0.7874 0.4064)
			(stroke
				(width 0.1524)
				(type default)
			)
			(layer "F.SilkS")
		)
		(fp_line
			(start 0.7874 0.4064)
			(end -0.7874 0.4064)
			(stroke
				(width 0.1524)
				(type default)
			)
			(layer "F.SilkS")
		)
		(fp_line
			(start -0.67945 -0.305054)
			(end -0.12065 -0.305054)
			(stroke
				(width 0.1)
				(type default)
			)
			(layer "F.Fab")
		)
		(fp_line
			(start -0.67945 0.3048)
			(end -0.67945 -0.305054)
			(stroke
				(width 0.1)
				(type default)
			)
			(layer "F.Fab")
		)
		(fp_line
			(start -0.12065 -0.305054)
			(end -0.12065 -0.2794)
			(stroke
				(width 0.1)
				(type default)
			)
			(layer "F.Fab")
		)
		(fp_line
			(start -0.12065 -0.2794)
			(end 0.12065 -0.2794)
			(stroke
				(width 0.1)
				(type default)
			)
			(layer "F.Fab")
		)
		(fp_line
			(start -0.12065 0.2794)
			(end -0.12065 0.3048)
			(stroke
				(width 0.1)
				(type default)
			)
			(layer "F.Fab")
		)
		(fp_line
			(start -0.12065 0.3048)
			(end -0.67945 0.3048)
			(stroke
				(width 0.1)
				(type default)
			)
			(layer "F.Fab")
		)
		(fp_line
			(start 0.120396 0.2794)
			(end -0.12065 0.2794)
			(stroke
				(width 0.1)
				(type default)
			)
			(layer "F.Fab")
		)
		(fp_line
			(start 0.120396 0.3048)
			(end 0.120396 0.2794)
			(stroke
				(width 0.1)
				(type default)
			)
			(layer "F.Fab")
		)
		(fp_line
			(start 0.12065 -0.3048)
			(end 0.67945 -0.3048)
			(stroke
				(width 0.1)
				(type default)
			)
			(layer "F.Fab")
		)
		(fp_line
			(start 0.12065 -0.2794)
			(end 0.12065 -0.3048)
			(stroke
				(width 0.1)
				(type default)
			)
			(layer "F.Fab")
		)
		(fp_line
			(start 0.67945 -0.3048)
			(end 0.67945 0.3048)
			(stroke
				(width 0.1)
				(type default)
			)
			(layer "F.Fab")
		)
		(fp_line
			(start 0.67945 0.3048)
			(end 0.120396 0.3048)
			(stroke
				(width 0.1)
				(type default)
			)
			(layer "F.Fab")
		)
		(pad "1" smd circle
			(at -0.40005 0)
			(size 0 0)
			(layers "F.Cu" "F.Mask" "F.Paste")
			(net "PWRGD_P3V3_SSD7")
		)
		(pad "2" smd circle
			(at 0.40005 0)
			(size 0 0)
			(layers "F.Cu" "F.Mask" "F.Paste")
			(net "PWRGD_P3V3_SSD7_R")
		)
	)
)
